(kicad_pcb
	(version 20260206)
	(generator "pcbnew")
	(generator_version "10.0")
	(general
		(thickness 1.6)
		(legacy_teardrops no)
	)
	(paper "A4")
	(title_block
		(title "panther-plus-userver — 13130-1b_20150205.brd")
		(comment 1 "Honey Badger (Wiwynn) / footprints 550-556 of 1509")
	)
	(layers
		(0 "F.Cu" signal "TOP")
		(4 "In1.Cu" signal "L2")
		(6 "In2.Cu" signal "L3")
		(8 "In3.Cu" signal "L4")
		(10 "In4.Cu" signal "L5")
		(12 "In5.Cu" signal "L6")
		(14 "In6.Cu" signal "L7")
		(16 "In7.Cu" signal "L8")
		(18 "In8.Cu" signal "L9")
		(20 "In9.Cu" signal "L10")
		(22 "In10.Cu" signal "L11")
		(2 "B.Cu" signal "BOTTOM")
		(9 "F.Adhes" user "F.Adhesive")
		(11 "B.Adhes" user "B.Adhesive")
		(13 "F.Paste" user "Package Geometry/Pastemask Top")
		(15 "B.Paste" user "Package Geometry/Pastemask Bottom")
		(5 "F.SilkS" user "Ref Des/Silkscreen Top")
		(7 "B.SilkS" user "Ref Des/Silkscreen Bottom")
		(1 "F.Mask" user "Board Geometry/Soldermask Top")
		(3 "B.Mask" user "Board Geometry/Soldermask Bottom")
		(17 "Dwgs.User" user "User.Drawings")
		(19 "Cmts.User" user "User.Comments")
		(21 "Eco1.User" user "User.Eco1")
		(23 "Eco2.User" user "User.Eco2")
		(25 "Edge.Cuts" user "Board Geometry/Outline")
		(27 "Margin" user)
		(31 "F.CrtYd" user "Package Geometry/Place Bound Top")
		(29 "B.CrtYd" user "Package Geometry/Place Bound Bottom")
		(35 "F.Fab" user "Ref Des/Assembly Top")
		(33 "B.Fab" user "Ref Des/Assembly Bottom")
	)
	(footprint ""
		(layer "F.Cu")
		(at 188.087 -50.673 180)
		(property "Reference" "R208"
			(at 0 0 180)
			(layer "F.SilkS")
			(hide yes)
			(effects
				(font
					(size 1.27 1.27)
				)
			)
		)
		(property "Value" "12K1R2F-L1-GP"
			(at 0.064008 -3.993896 180)
			(unlocked yes)
			(layer "F.Fab")
			(hide yes)
			(effects
				(font
					(size 1.016 1.016)
					(thickness 0.1524)
				)
			)
		)
		(property "Device Type" "R402H16"
			(at 0.064008 -5.517896 180)
			(unlocked yes)
			(layer "F.Fab")
			(hide yes)
			(effects
				(font
					(size 1.016 1.016)
					(thickness 0.1524)
				)
			)
		)
		(duplicate_pad_numbers_are_jumpers no)
		(fp_rect
			(start -0.381 0.8382)
			(end 0.381 -0.8382)
			(stroke
				(width 0)
				(type default)
			)
			(fill no)
			(layer "F.CrtYd")
		)
		(fp_rect
			(start -0.381 0.8382)
			(end 0.381 -0.8382)
			(stroke
				(width 0)
				(type default)
			)
			(fill no)
			(layer "F.Fab")
		)
		(pad "1" smd custom
			(at 0 -0.4318 180)
			(size 0.127 0.127)
			(layers "F.Cu" "F.Mask" "F.Paste")
			(net "PV_VDDR_VREF_RW")
			(options
				(clearance outline)
				(anchor circle)
			)
			(primitives
				(gr_poly
					(pts
						(arc
							(start -0.2032 -0.2794)
							(mid -0.239121 -0.264521)
							(end -0.254 -0.2286)
						)
						(arc
							(start -0.254 0.2286)
							(mid -0.239121 0.264521)
							(end -0.2032 0.2794)
						)
						(arc
							(start 0.2032 0.2794)
							(mid 0.239121 0.264521)
							(end 0.254 0.2286)
						)
						(arc
							(start 0.254 -0.2286)
							(mid 0.239121 -0.264521)
							(end 0.2032 -0.2794)
						)
					)
					(width 0)
					(fill yes)
				)
			)
		)
		(pad "2" smd custom
			(at 0 0.4318 180)
			(size 0.127 0.127)
			(layers "F.Cu" "F.Mask" "F.Paste")
			(net "GND")
			(options
				(clearance outline)
				(anchor circle)
			)
			(primitives
				(gr_poly
					(pts
						(arc
							(start -0.2032 -0.2794)
							(mid -0.239121 -0.264521)
							(end -0.254 -0.2286)
						)
						(arc
							(start -0.254 0.2286)
							(mid -0.239121 0.264521)
							(end -0.2032 0.2794)
						)
						(arc
							(start 0.2032 0.2794)
							(mid 0.239121 0.264521)
							(end 0.254 0.2286)
						)
						(arc
							(start 0.254 -0.2286)
							(mid 0.239121 -0.264521)
							(end 0.2032 -0.2794)
						)
					)
					(width 0)
					(fill yes)
				)
			)
		)
	)
	(footprint ""
		(layer "F.Cu")
		(at 151.257 -50.927 180)
		(property "Reference" "R484"
			(at 0 0 180)
			(layer "F.SilkS")
			(hide yes)
			(effects
				(font
					(size 1.27 1.27)
				)
			)
		)
		(property "Value" "10KR2F-2-GP"
			(at 1.7907 -1.1176 180)
			(unlocked yes)
			(layer "F.Fab")
			(hide yes)
			(effects
				(font
					(size 1.016 1.016)
					(thickness 0.1524)
				)
			)
		)
		(property "Device Type" "R402H16"
			(at 1.7907 -2.6416 180)
			(unlocked yes)
			(layer "F.Fab")
			(hide yes)
			(effects
				(font
					(size 1.016 1.016)
					(thickness 0.1524)
				)
			)
		)
		(duplicate_pad_numbers_are_jumpers no)
		(fp_rect
			(start -0.381 0.8382)
			(end 0.381 -0.8382)
			(stroke
				(width 0)
				(type default)
			)
			(fill no)
			(layer "F.CrtYd")
		)
		(fp_rect
			(start -0.381 0.8382)
			(end 0.381 -0.8382)
			(stroke
				(width 0)
				(type default)
			)
			(fill no)
			(layer "F.Fab")
		)
		(pad "1" smd custom
			(at 0 -0.4318 180)
			(size 0.127 0.127)
			(layers "F.Cu" "F.Mask" "F.Paste")
			(net "BUS_SW_OE#")
			(options
				(clearance outline)
				(anchor circle)
			)
			(primitives
				(gr_poly
					(pts
						(arc
							(start -0.2032 -0.2794)
							(mid -0.239121 -0.264521)
							(end -0.254 -0.2286)
						)
						(arc
							(start -0.254 0.2286)
							(mid -0.239121 0.264521)
							(end -0.2032 0.2794)
						)
						(arc
							(start 0.2032 0.2794)
							(mid 0.239121 0.264521)
							(end 0.254 0.2286)
						)
						(arc
							(start 0.254 -0.2286)
							(mid 0.239121 -0.264521)
							(end 0.2032 -0.2794)
						)
					)
					(width 0)
					(fill yes)
				)
			)
		)
		(pad "2" smd custom
			(at 0 0.4318 180)
			(size 0.127 0.127)
			(layers "F.Cu" "F.Mask" "F.Paste")
			(net "GND")
			(options
				(clearance outline)
				(anchor circle)
			)
			(primitives
				(gr_poly
					(pts
						(arc
							(start -0.2032 -0.2794)
							(mid -0.239121 -0.264521)
							(end -0.254 -0.2286)
						)
						(arc
							(start -0.254 0.2286)
							(mid -0.239121 0.264521)
							(end -0.2032 0.2794)
						)
						(arc
							(start 0.2032 0.2794)
							(mid 0.239121 0.264521)
							(end 0.254 0.2286)
						)
						(arc
							(start 0.254 -0.2286)
							(mid 0.239121 -0.264521)
							(end 0.2032 -0.2794)
						)
					)
					(width 0)
					(fill yes)
				)
			)
		)
	)
	(footprint ""
		(layer "F.Cu")
		(at 64.2112 -26.8732 -90)
		(property "Reference" "Q9"
			(at 0 0 270)
			(layer "F.SilkS")
			(hide yes)
			(effects
				(font
					(size 1.27 1.27)
				)
			)
		)
		(property "Value" "2N7002A-7-GP"
			(at 0.127 -8.9662 270)
			(unlocked yes)
			(layer "F.Fab")
			(hide yes)
			(effects
				(font
					(size 1.016 1.016)
					(thickness 0.1524)
				)
			)
		)
		(property "Device Type" "SOT23DGS2D4H48"
			(at 0.127 -10.4902 270)
			(unlocked yes)
			(layer "F.Fab")
			(hide yes)
			(effects
				(font
					(size 1.016 1.016)
					(thickness 0.1524)
				)
			)
		)
		(duplicate_pad_numbers_are_jumpers no)
		(fp_line
			(start -1.7145 0.4445)
			(end 1.7145 0.4445)
			(stroke
				(width 0.1524)
				(type default)
			)
			(layer "F.SilkS")
		)
		(fp_line
			(start 1.7145 0.4445)
			(end 1.7145 -0.4445)
			(stroke
				(width 0.1524)
				(type default)
			)
			(layer "F.SilkS")
		)
		(fp_line
			(start -1.7145 -0.4445)
			(end -1.7145 0.4445)
			(stroke
				(width 0.1524)
				(type default)
			)
			(layer "F.SilkS")
		)
		(fp_line
			(start 1.7145 -0.4445)
			(end -1.7145 -0.4445)
			(stroke
				(width 0.1524)
				(type default)
			)
			(layer "F.SilkS")
		)
		(fp_poly
			(pts
				(xy -1.4224 1.5621) (xy -1.4224 0.9017) (xy -1.7145 0.9017) (xy -1.7145 -0.9017) (xy -0.4699 -0.9017)
				(xy -0.4699 -1.5621) (xy 0.4699 -1.5621) (xy 0.4699 -0.9017) (xy 1.7145 -0.9017) (xy 1.7145 0.9017)
				(xy 1.4224 0.9017) (xy 1.4224 1.5621) (xy 0.4826 1.5621) (xy 0.4826 0.9017) (xy -0.4826 0.9017)
				(xy -0.4826 1.5621)
			)
			(stroke
				(width 0)
				(type default)
			)
			(fill no)
			(layer "F.CrtYd")
		)
		(fp_poly
			(pts
				(xy -1.4224 1.5621) (xy -1.4224 0.9017) (xy -1.7145 0.9017) (xy -1.7145 -0.9017) (xy -0.4699 -0.9017)
				(xy -0.4699 -1.5621) (xy 0.4699 -1.5621) (xy 0.4699 -0.9017) (xy 1.7145 -0.9017) (xy 1.7145 0.9017)
				(xy 1.4224 0.9017) (xy 1.4224 1.5621) (xy 0.4826 1.5621) (xy 0.4826 0.9017) (xy -0.4826 0.9017)
				(xy -0.4826 1.5621)
			)
			(stroke
				(width 0)
				(type default)
			)
			(fill no)
			(layer "F.Fab")
		)
		(pad "D" smd custom
			(at 0 -1.069086 270)
			(size 0.17145 0.17145)
			(layers "F.Cu" "F.Mask" "F.Paste")
			(net "SW_P1V8_EN_LV")
			(options
				(clearance outline)
				(anchor circle)
			)
			(primitives
				(gr_poly
					(pts
						(arc
							(start -0.1397 0.3683)
							(mid -0.283384 0.308784)
							(end -0.3429 0.1651)
						)
						(arc
							(start -0.3429 -0.1651)
							(mid -0.283384 -0.308784)
							(end -0.1397 -0.3683)
						)
						(arc
							(start 0.1397 -0.3683)
							(mid 0.283384 -0.308784)
							(end 0.3429 -0.1651)
						)
						(arc
							(start 0.3429 0.1651)
							(mid 0.283384 0.308784)
							(end 0.1397 0.3683)
						)
					)
					(width 0)
					(fill yes)
				)
			)
		)
		(pad "G" smd custom
			(at -0.94996 1.069086 270)
			(size 0.17145 0.17145)
			(layers "F.Cu" "F.Mask" "F.Paste")
			(net "SW_P1V8_EN_G")
			(options
				(clearance outline)
				(anchor circle)
			)
			(primitives
				(gr_poly
					(pts
						(arc
							(start -0.1397 0.3683)
							(mid -0.283384 0.308784)
							(end -0.3429 0.1651)
						)
						(arc
							(start -0.3429 -0.1651)
							(mid -0.283384 -0.308784)
							(end -0.1397 -0.3683)
						)
						(arc
							(start 0.1397 -0.3683)
							(mid 0.283384 -0.308784)
							(end 0.3429 -0.1651)
						)
						(arc
							(start 0.3429 0.1651)
							(mid 0.283384 0.308784)
							(end 0.1397 0.3683)
						)
					)
					(width 0)
					(fill yes)
				)
			)
		)
		(pad "S" smd custom
			(at 0.94996 1.069086 270)
			(size 0.17145 0.17145)
			(layers "F.Cu" "F.Mask" "F.Paste")
			(net "SW_P1V8_EN_S")
			(options
				(clearance outline)
				(anchor circle)
			)
			(primitives
				(gr_poly
					(pts
						(arc
							(start -0.1397 0.3683)
							(mid -0.283384 0.308784)
							(end -0.3429 0.1651)
						)
						(arc
							(start -0.3429 -0.1651)
							(mid -0.283384 -0.308784)
							(end -0.1397 -0.3683)
						)
						(arc
							(start 0.1397 -0.3683)
							(mid 0.283384 -0.308784)
							(end 0.3429 -0.1651)
						)
						(arc
							(start 0.3429 0.1651)
							(mid 0.283384 0.308784)
							(end 0.1397 0.3683)
						)
					)
					(width 0)
					(fill yes)
				)
			)
		)
	)
	(footprint ""
		(layer "F.Cu")
		(at 23.749 -48.895 90)
		(property "Reference" "PR81"
			(at 0 0 90)
			(layer "F.SilkS")
			(hide yes)
			(effects
				(font
					(size 1.27 1.27)
				)
			)
		)
		(property "Value" "10R2F-L-GP"
			(at 1.7907 -1.1176 90)
			(unlocked yes)
			(layer "F.Fab")
			(hide yes)
			(effects
				(font
					(size 1.016 1.016)
					(thickness 0.1524)
				)
			)
		)
		(property "Device Type" "R402H14"
			(at 1.7907 -2.6416 90)
			(unlocked yes)
			(layer "F.Fab")
			(hide yes)
			(effects
				(font
					(size 1.016 1.016)
					(thickness 0.1524)
				)
			)
		)
		(duplicate_pad_numbers_are_jumpers no)
		(fp_rect
			(start -0.381 0.8382)
			(end 0.381 -0.8382)
			(stroke
				(width 0)
				(type default)
			)
			(fill no)
			(layer "F.CrtYd")
		)
		(fp_rect
			(start -0.381 0.8382)
			(end 0.381 -0.8382)
			(stroke
				(width 0)
				(type default)
			)
			(fill no)
			(layer "F.Fab")
		)
		(pad "1" smd custom
			(at 0 -0.4318 90)
			(size 0.127 0.127)
			(layers "F.Cu" "F.Mask" "F.Paste")
			(net "VR_PVCCP_ISUMN_R2")
			(options
				(clearance outline)
				(anchor circle)
			)
			(primitives
				(gr_poly
					(pts
						(arc
							(start -0.2032 -0.2794)
							(mid -0.239121 -0.264521)
							(end -0.254 -0.2286)
						)
						(arc
							(start -0.254 0.2286)
							(mid -0.239121 0.264521)
							(end -0.2032 0.2794)
						)
						(arc
							(start 0.2032 0.2794)
							(mid 0.239121 0.264521)
							(end 0.254 0.2286)
						)
						(arc
							(start 0.254 -0.2286)
							(mid 0.239121 -0.264521)
							(end 0.2032 -0.2794)
						)
					)
					(width 0)
					(fill yes)
				)
			)
		)
		(pad "2" smd custom
			(at 0 0.4318 90)
			(size 0.127 0.127)
			(layers "F.Cu" "F.Mask" "F.Paste")
			(net "VR_PVCCP_ISUMN")
			(options
				(clearance outline)
				(anchor circle)
			)
			(primitives
				(gr_poly
					(pts
						(arc
							(start -0.2032 -0.2794)
							(mid -0.239121 -0.264521)
							(end -0.254 -0.2286)
						)
						(arc
							(start -0.254 0.2286)
							(mid -0.239121 0.264521)
							(end -0.2032 0.2794)
						)
						(arc
							(start 0.2032 0.2794)
							(mid 0.239121 0.264521)
							(end 0.254 0.2286)
						)
						(arc
							(start 0.254 -0.2286)
							(mid 0.239121 -0.264521)
							(end 0.2032 -0.2794)
						)
					)
					(width 0)
					(fill yes)
				)
			)
		)
	)
	(footprint ""
		(layer "F.Cu")
		(at 105.8926 -20.701 90)
		(property "Reference" "R162"
			(at 0 0 90)
			(layer "F.SilkS")
			(hide yes)
			(effects
				(font
					(size 1.27 1.27)
				)
			)
		)
		(property "Value" "100KR2F-L1-GP"
			(at 0.064008 -3.993896 90)
			(unlocked yes)
			(layer "F.Fab")
			(hide yes)
			(effects
				(font
					(size 1.016 1.016)
					(thickness 0.1524)
				)
			)
		)
		(property "Device Type" "R402H16"
			(at 0.064008 -5.517896 90)
			(unlocked yes)
			(layer "F.Fab")
			(hide yes)
			(effects
				(font
					(size 1.016 1.016)
					(thickness 0.1524)
				)
			)
		)
		(duplicate_pad_numbers_are_jumpers no)
		(fp_rect
			(start -0.381 0.8382)
			(end 0.381 -0.8382)
			(stroke
				(width 0)
				(type default)
			)
			(fill no)
			(layer "F.CrtYd")
		)
		(fp_rect
			(start -0.381 0.8382)
			(end 0.381 -0.8382)
			(stroke
				(width 0)
				(type default)
			)
			(fill no)
			(layer "F.Fab")
		)
		(pad "1" smd custom
			(at 0 -0.4318 90)
			(size 0.127 0.127)
			(layers "F.Cu" "F.Mask" "F.Paste")
			(net "GND")
			(options
				(clearance outline)
				(anchor circle)
			)
			(primitives
				(gr_poly
					(pts
						(arc
							(start -0.2032 -0.2794)
							(mid -0.239121 -0.264521)
							(end -0.254 -0.2286)
						)
						(arc
							(start -0.254 0.2286)
							(mid -0.239121 0.264521)
							(end -0.2032 0.2794)
						)
						(arc
							(start 0.2032 0.2794)
							(mid 0.239121 0.264521)
							(end 0.254 0.2286)
						)
						(arc
							(start 0.254 -0.2286)
							(mid 0.239121 -0.264521)
							(end 0.2032 -0.2794)
						)
					)
					(width 0)
					(fill yes)
				)
			)
		)
		(pad "2" smd custom
			(at 0 0.4318 90)
			(size 0.127 0.127)
			(layers "F.Cu" "F.Mask" "F.Paste")
			(net "M_B_R_RESET#")
			(options
				(clearance outline)
				(anchor circle)
			)
			(primitives
				(gr_poly
					(pts
						(arc
							(start -0.2032 -0.2794)
							(mid -0.239121 -0.264521)
							(end -0.254 -0.2286)
						)
						(arc
							(start -0.254 0.2286)
							(mid -0.239121 0.264521)
							(end -0.2032 0.2794)
						)
						(arc
							(start 0.2032 0.2794)
							(mid 0.239121 0.264521)
							(end 0.254 0.2286)
						)
						(arc
							(start 0.254 -0.2286)
							(mid 0.239121 -0.264521)
							(end 0.2032 -0.2794)
						)
					)
					(width 0)
					(fill yes)
				)
			)
		)
	)
	(footprint ""
		(layer "F.Cu")
		(at 178.689 -48.895 90)
		(property "Reference" "C84"
			(at 0 0 90)
			(layer "F.SilkS")
			(hide yes)
			(effects
				(font
					(size 1.27 1.27)
				)
			)
		)
		(property "Value" "SCD1U16V2KX-3GP"
			(at 1.1811 -2.7051 90)
			(unlocked yes)
			(layer "F.Fab")
			(hide yes)
			(effects
				(font
					(size 1.016 1.016)
					(thickness 0.1524)
				)
			)
		)
		(property "Device Type" "C402H22"
			(at 1.1811 -4.2291 90)
			(unlocked yes)
			(layer "F.Fab")
			(hide yes)
			(effects
				(font
					(size 1.016 1.016)
					(thickness 0.1524)
				)
			)
		)
		(duplicate_pad_numbers_are_jumpers no)
		(fp_rect
			(start -0.381 0.7366)
			(end 0.381 -0.7366)
			(stroke
				(width 0)
				(type default)
			)
			(fill no)
			(layer "F.CrtYd")
		)
		(fp_rect
			(start -0.381 0.7366)
			(end 0.381 -0.7366)
			(stroke
				(width 0)
				(type default)
			)
			(fill no)
			(layer "F.Fab")
		)
		(pad "1" smd custom
			(at 0 -0.4572 90)
			(size 0.1143 0.1143)
			(layers "F.Cu" "F.Mask" "F.Paste")
			(net "P3V3_STBY")
			(options
				(clearance outline)
				(anchor circle)
			)
			(primitives
				(gr_poly
					(pts
						(arc
							(start -0.254 -0.1778)
							(mid -0.239121 -0.213721)
							(end -0.2032 -0.2286)
						)
						(arc
							(start 0.2032 -0.2286)
							(mid 0.239121 -0.213721)
							(end 0.254 -0.1778)
						)
						(arc
							(start 0.254 0.1778)
							(mid 0.239121 0.213721)
							(end 0.2032 0.2286)
						)
						(arc
							(start -0.2032 0.2286)
							(mid -0.239121 0.213721)
							(end -0.254 0.1778)
						)
					)
					(width 0)
					(fill yes)
				)
			)
		)
		(pad "2" smd custom
			(at 0 0.4572 90)
			(size 0.1143 0.1143)
			(layers "F.Cu" "F.Mask" "F.Paste")
			(net "GND")
			(options
				(clearance outline)
				(anchor circle)
			)
			(primitives
				(gr_poly
					(pts
						(arc
							(start -0.254 -0.1778)
							(mid -0.239121 -0.213721)
							(end -0.2032 -0.2286)
						)
						(arc
							(start 0.2032 -0.2286)
							(mid 0.239121 -0.213721)
							(end 0.254 -0.1778)
						)
						(arc
							(start 0.254 0.1778)
							(mid 0.239121 0.213721)
							(end 0.2032 0.2286)
						)
						(arc
							(start -0.2032 0.2286)
							(mid -0.239121 0.213721)
							(end -0.254 0.1778)
						)
					)
					(width 0)
					(fill yes)
				)
			)
		)
	)
	(footprint ""
		(layer "F.Cu")
		(at 54.864 -42.164)
		(property "Reference" "C19"
			(at 0 0 0)
			(layer "F.SilkS")
			(hide yes)
			(effects
				(font
					(size 1.27 1.27)
				)
			)
		)
		(property "Value" "SCD47U25V2KX-GP"
			(at 1.8923 -1.2065 0)
			(unlocked yes)
			(layer "F.Fab")
			(hide yes)
			(effects
				(font
					(size 1.016 1.016)
					(thickness 0.1524)
				)
			)
		)
		(property "Device Type" "C402H24"
			(at 1.8923 -2.7305 0)
			(unlocked yes)
			(layer "F.Fab")
			(hide yes)
			(effects
				(font
					(size 1.016 1.016)
					(thickness 0.1524)
				)
			)
		)
		(duplicate_pad_numbers_are_jumpers no)
		(fp_rect
			(start -0.381 0.7366)
			(end 0.381 -0.7366)
			(stroke
				(width 0)
				(type default)
			)
			(fill no)
			(layer "F.CrtYd")
		)
		(fp_rect
			(start -0.381 0.7366)
			(end 0.381 -0.7366)
			(stroke
				(width 0)
				(type default)
			)
			(fill no)
			(layer "F.Fab")
		)
		(pad "1" smd custom
			(at 0 -0.4572)
			(size 0.1143 0.1143)
			(layers "F.Cu" "F.Mask" "F.Paste")
			(net "SW_P3V3_EN_LV_D")
			(options
				(clearance outline)
				(anchor circle)
			)
			(primitives
				(gr_poly
					(pts
						(arc
							(start -0.254 -0.1778)
							(mid -0.239121 -0.213721)
							(end -0.2032 -0.2286)
						)
						(arc
							(start 0.2032 -0.2286)
							(mid 0.239121 -0.213721)
							(end 0.254 -0.1778)
						)
						(arc
							(start 0.254 0.1778)
							(mid 0.239121 0.213721)
							(end 0.2032 0.2286)
						)
						(arc
							(start -0.2032 0.2286)
							(mid -0.239121 0.213721)
							(end -0.254 0.1778)
						)
					)
					(width 0)
					(fill yes)
				)
			)
		)
		(pad "2" smd custom
			(at 0 0.4572)
			(size 0.1143 0.1143)
			(layers "F.Cu" "F.Mask" "F.Paste")
			(net "P3V3")
			(options
				(clearance outline)
				(anchor circle)
			)
			(primitives
				(gr_poly
					(pts
						(arc
							(start -0.254 -0.1778)
							(mid -0.239121 -0.213721)
							(end -0.2032 -0.2286)
						)
						(arc
							(start 0.2032 -0.2286)
							(mid 0.239121 -0.213721)
							(end 0.254 -0.1778)
						)
						(arc
							(start 0.254 0.1778)
							(mid 0.239121 0.213721)
							(end 0.2032 0.2286)
						)
						(arc
							(start -0.2032 0.2286)
							(mid -0.239121 0.213721)
							(end -0.254 0.1778)
						)
					)
					(width 0)
					(fill yes)
				)
			)
		)
	)
)
